(kicad_pcb
	(version 20260206)
	(generator "pcbnew")
	(generator_version "10.0")
	(general
		(thickness 1.6)
		(legacy_teardrops no)
	)
	(paper "A4")
	(title_block
		(title "01162023_DA0F0TEBIF0_F0T_Expander_BD_F_brd_V02_OCP.brd")
		(comment 1 "Grand Teton / footprints 7296-7301 of 9728")
	)
	(layers
		(0 "F.Cu" signal "TOP")
		(4 "In1.Cu" signal "GND")
		(6 "In2.Cu" signal "VCC")
		(8 "In3.Cu" signal "VCC1")
		(10 "In4.Cu" signal "GND1")
		(12 "In5.Cu" signal "IN1")
		(14 "In6.Cu" signal "GND2")
		(16 "In7.Cu" signal "IN2")
		(18 "In8.Cu" signal "GND3")
		(20 "In9.Cu" signal "IN3")
		(22 "In10.Cu" signal "GND4")
		(24 "In11.Cu" signal "IN4")
		(26 "In12.Cu" signal "GND5")
		(28 "In13.Cu" signal "IN5")
		(30 "In14.Cu" signal "GND6")
		(32 "In15.Cu" signal "IN6")
		(34 "In16.Cu" signal "GND7")
		(2 "B.Cu" signal "BOTTOM")
		(9 "F.Adhes" user "F.Adhesive")
		(11 "B.Adhes" user "B.Adhesive")
		(13 "F.Paste" user "Package Geometry/Pastemask Top")
		(15 "B.Paste" user "Package Geometry/Pastemask Bottom")
		(5 "F.SilkS" user "Ref Des/Silkscreen Top")
		(7 "B.SilkS" user "Ref Des/Silkscreen Bottom")
		(1 "F.Mask" user "Board Geometry/Soldermask Top")
		(3 "B.Mask" user "Board Geometry/Soldermask Bottom")
		(17 "Dwgs.User" user "User.Drawings")
		(19 "Cmts.User" user "User.Comments")
		(21 "Eco1.User" user "User.Eco1")
		(23 "Eco2.User" user "User.Eco2")
		(25 "Edge.Cuts" user "Board Geometry/Outline")
		(27 "Margin" user)
		(31 "F.CrtYd" user "Package Geometry/Place Bound Top")
		(29 "B.CrtYd" user "Package Geometry/Place Bound Bottom")
		(35 "F.Fab" user "Ref Des/Assembly Top")
		(33 "B.Fab" user "Ref Des/Assembly Bottom")
	)
	(footprint ""
		(layer "B.Cu")
		(at 217.235786 -220.334586)
		(property "Reference" "R1497"
			(at 0 0 0)
			(layer "B.SilkS")
			(hide yes)
			(effects
				(font
					(size 1.27 1.27)
				)
				(justify mirror)
			)
		)
		(property "Value" ""
			(at 0 0 0)
			(layer "B.Fab")
			(effects
				(font
					(size 1.27 1.27)
				)
				(justify mirror)
			)
		)
		(duplicate_pad_numbers_are_jumpers no)
		(fp_line
			(start -0.7874 -0.4064)
			(end -0.7874 0.4064)
			(stroke
				(width 0.1524)
				(type default)
			)
			(layer "B.SilkS")
		)
		(fp_line
			(start -0.7874 0.4064)
			(end 0.7874 0.4064)
			(stroke
				(width 0.1524)
				(type default)
			)
			(layer "B.SilkS")
		)
		(fp_line
			(start 0.7874 -0.4064)
			(end -0.7874 -0.4064)
			(stroke
				(width 0.1524)
				(type default)
			)
			(layer "B.SilkS")
		)
		(fp_line
			(start 0.7874 0.4064)
			(end 0.7874 -0.4064)
			(stroke
				(width 0.1524)
				(type default)
			)
			(layer "B.SilkS")
		)
		(fp_line
			(start -0.67945 -0.3048)
			(end -0.67945 0.3048)
			(stroke
				(width 0.1)
				(type default)
			)
			(layer "B.Fab")
		)
		(fp_line
			(start -0.67945 0.3048)
			(end -0.120396 0.3048)
			(stroke
				(width 0.1)
				(type default)
			)
			(layer "B.Fab")
		)
		(fp_line
			(start -0.12065 -0.3048)
			(end -0.67945 -0.3048)
			(stroke
				(width 0.1)
				(type default)
			)
			(layer "B.Fab")
		)
		(fp_line
			(start -0.12065 -0.2794)
			(end -0.12065 -0.3048)
			(stroke
				(width 0.1)
				(type default)
			)
			(layer "B.Fab")
		)
		(fp_line
			(start -0.120396 0.2794)
			(end 0.12065 0.2794)
			(stroke
				(width 0.1)
				(type default)
			)
			(layer "B.Fab")
		)
		(fp_line
			(start -0.120396 0.3048)
			(end -0.120396 0.2794)
			(stroke
				(width 0.1)
				(type default)
			)
			(layer "B.Fab")
		)
		(fp_line
			(start 0.12065 -0.305054)
			(end 0.12065 -0.2794)
			(stroke
				(width 0.1)
				(type default)
			)
			(layer "B.Fab")
		)
		(fp_line
			(start 0.12065 -0.2794)
			(end -0.12065 -0.2794)
			(stroke
				(width 0.1)
				(type default)
			)
			(layer "B.Fab")
		)
		(fp_line
			(start 0.12065 0.2794)
			(end 0.12065 0.3048)
			(stroke
				(width 0.1)
				(type default)
			)
			(layer "B.Fab")
		)
		(fp_line
			(start 0.12065 0.3048)
			(end 0.67945 0.3048)
			(stroke
				(width 0.1)
				(type default)
			)
			(layer "B.Fab")
		)
		(fp_line
			(start 0.67945 -0.305054)
			(end 0.12065 -0.305054)
			(stroke
				(width 0.1)
				(type default)
			)
			(layer "B.Fab")
		)
		(fp_line
			(start 0.67945 0.3048)
			(end 0.67945 -0.305054)
			(stroke
				(width 0.1)
				(type default)
			)
			(layer "B.Fab")
		)
		(pad "1" smd circle
			(at 0.40005 0 180)
			(size 0 0)
			(layers "B.Cu" "B.Mask" "B.Paste")
			(net "SMB_PEX_SDA")
		)
		(pad "2" smd circle
			(at -0.40005 0 180)
			(size 0 0)
			(layers "B.Cu" "B.Mask" "B.Paste")
			(net "SMB_PEX_R_SDA")
		)
	)
	(footprint ""
		(layer "B.Cu")
		(at 291.360606 -305.557936 -90)
		(property "Reference" "C3293"
			(at 0 0 90)
			(layer "B.SilkS")
			(hide yes)
			(effects
				(font
					(size 1.27 1.27)
				)
				(justify mirror)
			)
		)
		(property "Value" ""
			(at 0 0 90)
			(layer "B.Fab")
			(effects
				(font
					(size 1.27 1.27)
				)
				(justify mirror)
			)
		)
		(duplicate_pad_numbers_are_jumpers no)
		(fp_line
			(start -1.2954 0.5842)
			(end 1.2954 0.5842)
			(stroke
				(width 0.1524)
				(type default)
			)
			(layer "B.SilkS")
		)
		(fp_line
			(start 1.2954 0.5842)
			(end 1.2954 -0.5842)
			(stroke
				(width 0.1524)
				(type default)
			)
			(layer "B.SilkS")
		)
		(fp_line
			(start -1.2954 -0.5842)
			(end -1.2954 0.5842)
			(stroke
				(width 0.1524)
				(type default)
			)
			(layer "B.SilkS")
		)
		(fp_line
			(start 1.2954 -0.5842)
			(end -1.2954 -0.5842)
			(stroke
				(width 0.1524)
				(type default)
			)
			(layer "B.SilkS")
		)
		(fp_line
			(start -0.8636 0.4572)
			(end 0.8636 0.4572)
			(stroke
				(width 0.1)
				(type default)
			)
			(layer "B.Fab")
		)
		(fp_line
			(start 0.8636 0.4572)
			(end 0.8636 0.4064)
			(stroke
				(width 0.1)
				(type default)
			)
			(layer "B.Fab")
		)
		(fp_line
			(start -1.1938 0.4064)
			(end -0.8636 0.4064)
			(stroke
				(width 0.1)
				(type default)
			)
			(layer "B.Fab")
		)
		(fp_line
			(start -0.8636 0.4064)
			(end -0.8636 0.4572)
			(stroke
				(width 0.1)
				(type default)
			)
			(layer "B.Fab")
		)
		(fp_line
			(start 0.8636 0.4064)
			(end 1.1938 0.4064)
			(stroke
				(width 0.1)
				(type default)
			)
			(layer "B.Fab")
		)
		(fp_line
			(start 1.1938 0.4064)
			(end 1.1938 -0.4064)
			(stroke
				(width 0.1)
				(type default)
			)
			(layer "B.Fab")
		)
		(fp_line
			(start -1.1938 -0.4064)
			(end -1.1938 0.4064)
			(stroke
				(width 0.1)
				(type default)
			)
			(layer "B.Fab")
		)
		(fp_line
			(start -0.8636 -0.4064)
			(end -1.1938 -0.4064)
			(stroke
				(width 0.1)
				(type default)
			)
			(layer "B.Fab")
		)
		(fp_line
			(start 0.8636 -0.4064)
			(end 0.8636 -0.4572)
			(stroke
				(width 0.1)
				(type default)
			)
			(layer "B.Fab")
		)
		(fp_line
			(start 1.1938 -0.4064)
			(end 0.8636 -0.4064)
			(stroke
				(width 0.1)
				(type default)
			)
			(layer "B.Fab")
		)
		(fp_line
			(start -0.8636 -0.4572)
			(end -0.8636 -0.4064)
			(stroke
				(width 0.1)
				(type default)
			)
			(layer "B.Fab")
		)
		(fp_line
			(start 0.8636 -0.4572)
			(end -0.8636 -0.4572)
			(stroke
				(width 0.1)
				(type default)
			)
			(layer "B.Fab")
		)
		(pad "1" smd rect
			(at 0.7366 0 180)
			(size 0.7112 0.8128)
			(layers "B.Cu" "B.Mask" "B.Paste")
			(net "P1V25_SERDES_VDDPLL_PEX2")
		)
		(pad "2" smd rect
			(at -0.7366 0 180)
			(size 0.7112 0.8128)
			(layers "B.Cu" "B.Mask" "B.Paste")
			(net "GND")
		)
	)
	(footprint ""
		(layer "B.Cu")
		(at 410.480256 -295.221914)
		(property "Reference" "C1865"
			(at 0 0 0)
			(layer "B.SilkS")
			(hide yes)
			(effects
				(font
					(size 1.27 1.27)
				)
				(justify mirror)
			)
		)
		(property "Value" ""
			(at 0 0 0)
			(layer "B.Fab")
			(effects
				(font
					(size 1.27 1.27)
				)
				(justify mirror)
			)
		)
		(duplicate_pad_numbers_are_jumpers no)
		(fp_line
			(start -1.2954 -0.5842)
			(end -1.2954 0.5842)
			(stroke
				(width 0.1524)
				(type default)
			)
			(layer "B.SilkS")
		)
		(fp_line
			(start -1.2954 0.5842)
			(end 1.2954 0.5842)
			(stroke
				(width 0.1524)
				(type default)
			)
			(layer "B.SilkS")
		)
		(fp_line
			(start 1.2954 -0.5842)
			(end -1.2954 -0.5842)
			(stroke
				(width 0.1524)
				(type default)
			)
			(layer "B.SilkS")
		)
		(fp_line
			(start 1.2954 0.5842)
			(end 1.2954 -0.5842)
			(stroke
				(width 0.1524)
				(type default)
			)
			(layer "B.SilkS")
		)
		(fp_line
			(start -1.1938 -0.4064)
			(end -1.1938 0.4064)
			(stroke
				(width 0.1)
				(type default)
			)
			(layer "B.Fab")
		)
		(fp_line
			(start -1.1938 0.4064)
			(end -0.8636 0.4064)
			(stroke
				(width 0.1)
				(type default)
			)
			(layer "B.Fab")
		)
		(fp_line
			(start -0.8636 -0.4572)
			(end -0.8636 -0.4064)
			(stroke
				(width 0.1)
				(type default)
			)
			(layer "B.Fab")
		)
		(fp_line
			(start -0.8636 -0.4064)
			(end -1.1938 -0.4064)
			(stroke
				(width 0.1)
				(type default)
			)
			(layer "B.Fab")
		)
		(fp_line
			(start -0.8636 0.4064)
			(end -0.8636 0.4572)
			(stroke
				(width 0.1)
				(type default)
			)
			(layer "B.Fab")
		)
		(fp_line
			(start -0.8636 0.4572)
			(end 0.8636 0.4572)
			(stroke
				(width 0.1)
				(type default)
			)
			(layer "B.Fab")
		)
		(fp_line
			(start 0.8636 -0.4572)
			(end -0.8636 -0.4572)
			(stroke
				(width 0.1)
				(type default)
			)
			(layer "B.Fab")
		)
		(fp_line
			(start 0.8636 -0.4064)
			(end 0.8636 -0.4572)
			(stroke
				(width 0.1)
				(type default)
			)
			(layer "B.Fab")
		)
		(fp_line
			(start 0.8636 0.4064)
			(end 1.1938 0.4064)
			(stroke
				(width 0.1)
				(type default)
			)
			(layer "B.Fab")
		)
		(fp_line
			(start 0.8636 0.4572)
			(end 0.8636 0.4064)
			(stroke
				(width 0.1)
				(type default)
			)
			(layer "B.Fab")
		)
		(fp_line
			(start 1.1938 -0.4064)
			(end 0.8636 -0.4064)
			(stroke
				(width 0.1)
				(type default)
			)
			(layer "B.Fab")
		)
		(fp_line
			(start 1.1938 0.4064)
			(end 1.1938 -0.4064)
			(stroke
				(width 0.1)
				(type default)
			)
			(layer "B.Fab")
		)
		(pad "1" smd rect
			(at 0.7366 0 270)
			(size 0.7112 0.8128)
			(layers "B.Cu" "B.Mask" "B.Paste")
			(net "P0V8_PEX3")
		)
		(pad "2" smd rect
			(at -0.7366 0 270)
			(size 0.7112 0.8128)
			(layers "B.Cu" "B.Mask" "B.Paste")
			(net "GND")
		)
	)
	(footprint ""
		(layer "B.Cu")
		(at 337.6549 -308.613556 90)
		(property "Reference" "C4302"
			(at 0 0 90)
			(layer "B.SilkS")
			(hide yes)
			(effects
				(font
					(size 1.27 1.27)
				)
				(justify mirror)
			)
		)
		(property "Value" ""
			(at 0 0 90)
			(layer "B.Fab")
			(effects
				(font
					(size 1.27 1.27)
				)
				(justify mirror)
			)
		)
		(duplicate_pad_numbers_are_jumpers no)
		(fp_line
			(start 1.2954 -0.5842)
			(end -1.2954 -0.5842)
			(stroke
				(width 0.1524)
				(type default)
			)
			(layer "B.SilkS")
		)
		(fp_line
			(start -1.2954 -0.5842)
			(end -1.2954 0.5842)
			(stroke
				(width 0.1524)
				(type default)
			)
			(layer "B.SilkS")
		)
		(fp_line
			(start 1.2954 0.5842)
			(end 1.2954 -0.5842)
			(stroke
				(width 0.1524)
				(type default)
			)
			(layer "B.SilkS")
		)
		(fp_line
			(start -1.2954 0.5842)
			(end 1.2954 0.5842)
			(stroke
				(width 0.1524)
				(type default)
			)
			(layer "B.SilkS")
		)
		(fp_line
			(start 0.8636 -0.4572)
			(end -0.8636 -0.4572)
			(stroke
				(width 0.1)
				(type default)
			)
			(layer "B.Fab")
		)
		(fp_line
			(start -0.8636 -0.4572)
			(end -0.8636 -0.4064)
			(stroke
				(width 0.1)
				(type default)
			)
			(layer "B.Fab")
		)
		(fp_line
			(start 1.1938 -0.4064)
			(end 0.8636 -0.4064)
			(stroke
				(width 0.1)
				(type default)
			)
			(layer "B.Fab")
		)
		(fp_line
			(start 0.8636 -0.4064)
			(end 0.8636 -0.4572)
			(stroke
				(width 0.1)
				(type default)
			)
			(layer "B.Fab")
		)
		(fp_line
			(start -0.8636 -0.4064)
			(end -1.1938 -0.4064)
			(stroke
				(width 0.1)
				(type default)
			)
			(layer "B.Fab")
		)
		(fp_line
			(start -1.1938 -0.4064)
			(end -1.1938 0.4064)
			(stroke
				(width 0.1)
				(type default)
			)
			(layer "B.Fab")
		)
		(fp_line
			(start 1.1938 0.4064)
			(end 1.1938 -0.4064)
			(stroke
				(width 0.1)
				(type default)
			)
			(layer "B.Fab")
		)
		(fp_line
			(start 0.8636 0.4064)
			(end 1.1938 0.4064)
			(stroke
				(width 0.1)
				(type default)
			)
			(layer "B.Fab")
		)
		(fp_line
			(start -0.8636 0.4064)
			(end -0.8636 0.4572)
			(stroke
				(width 0.1)
				(type default)
			)
			(layer "B.Fab")
		)
		(fp_line
			(start -1.1938 0.4064)
			(end -0.8636 0.4064)
			(stroke
				(width 0.1)
				(type default)
			)
			(layer "B.Fab")
		)
		(fp_line
			(start 0.8636 0.4572)
			(end 0.8636 0.4064)
			(stroke
				(width 0.1)
				(type default)
			)
			(layer "B.Fab")
		)
		(fp_line
			(start -0.8636 0.4572)
			(end 0.8636 0.4572)
			(stroke
				(width 0.1)
				(type default)
			)
			(layer "B.Fab")
		)
		(pad "1" smd rect
			(at 0.7366 0)
			(size 0.7112 0.8128)
			(layers "B.Cu" "B.Mask" "B.Paste")
			(net "P0V8_PEX2")
		)
		(pad "2" smd rect
			(at -0.7366 0)
			(size 0.7112 0.8128)
			(layers "B.Cu" "B.Mask" "B.Paste")
			(net "GND")
		)
	)
	(footprint ""
		(layer "B.Cu")
		(at 257.052064 -80.364076)
		(property "Reference" "C2634"
			(at 0 0 0)
			(layer "B.SilkS")
			(hide yes)
			(effects
				(font
					(size 1.27 1.27)
				)
				(justify mirror)
			)
		)
		(property "Value" ""
			(at 0 0 0)
			(layer "B.Fab")
			(effects
				(font
					(size 1.27 1.27)
				)
				(justify mirror)
			)
		)
		(duplicate_pad_numbers_are_jumpers no)
		(fp_line
			(start -1.2954 -0.5842)
			(end -1.2954 0.5842)
			(stroke
				(width 0.1524)
				(type default)
			)
			(layer "B.SilkS")
		)
		(fp_line
			(start -1.2954 0.5842)
			(end 1.2954 0.5842)
			(stroke
				(width 0.1524)
				(type default)
			)
			(layer "B.SilkS")
		)
		(fp_line
			(start 1.2954 -0.5842)
			(end -1.2954 -0.5842)
			(stroke
				(width 0.1524)
				(type default)
			)
			(layer "B.SilkS")
		)
		(fp_line
			(start 1.2954 0.5842)
			(end 1.2954 -0.5842)
			(stroke
				(width 0.1524)
				(type default)
			)
			(layer "B.SilkS")
		)
		(fp_line
			(start -1.1938 -0.4064)
			(end -1.1938 0.4064)
			(stroke
				(width 0.1)
				(type default)
			)
			(layer "B.Fab")
		)
		(fp_line
			(start -1.1938 0.4064)
			(end -0.8636 0.4064)
			(stroke
				(width 0.1)
				(type default)
			)
			(layer "B.Fab")
		)
		(fp_line
			(start -0.8636 -0.4572)
			(end -0.8636 -0.4064)
			(stroke
				(width 0.1)
				(type default)
			)
			(layer "B.Fab")
		)
		(fp_line
			(start -0.8636 -0.4064)
			(end -1.1938 -0.4064)
			(stroke
				(width 0.1)
				(type default)
			)
			(layer "B.Fab")
		)
		(fp_line
			(start -0.8636 0.4064)
			(end -0.8636 0.4572)
			(stroke
				(width 0.1)
				(type default)
			)
			(layer "B.Fab")
		)
		(fp_line
			(start -0.8636 0.4572)
			(end 0.8636 0.4572)
			(stroke
				(width 0.1)
				(type default)
			)
			(layer "B.Fab")
		)
		(fp_line
			(start 0.8636 -0.4572)
			(end -0.8636 -0.4572)
			(stroke
				(width 0.1)
				(type default)
			)
			(layer "B.Fab")
		)
		(fp_line
			(start 0.8636 -0.4064)
			(end 0.8636 -0.4572)
			(stroke
				(width 0.1)
				(type default)
			)
			(layer "B.Fab")
		)
		(fp_line
			(start 0.8636 0.4064)
			(end 1.1938 0.4064)
			(stroke
				(width 0.1)
				(type default)
			)
			(layer "B.Fab")
		)
		(fp_line
			(start 0.8636 0.4572)
			(end 0.8636 0.4064)
			(stroke
				(width 0.1)
				(type default)
			)
			(layer "B.Fab")
		)
		(fp_line
			(start 1.1938 -0.4064)
			(end 0.8636 -0.4064)
			(stroke
				(width 0.1)
				(type default)
			)
			(layer "B.Fab")
		)
		(fp_line
			(start 1.1938 0.4064)
			(end 1.1938 -0.4064)
			(stroke
				(width 0.1)
				(type default)
			)
			(layer "B.Fab")
		)
		(pad "1" smd rect
			(at 0.7366 0 270)
			(size 0.7112 0.8128)
			(layers "B.Cu" "B.Mask" "B.Paste")
			(net "P3V3_CLK_GEN_VDDA100M_CK440")
		)
		(pad "2" smd rect
			(at -0.7366 0 270)
			(size 0.7112 0.8128)
			(layers "B.Cu" "B.Mask" "B.Paste")
			(net "GND")
		)
	)
	(footprint ""
		(layer "B.Cu")
		(at 217.247724 -216.388696 180)
		(property "Reference" "R4861"
			(at 0 0 0)
			(layer "B.SilkS")
			(hide yes)
			(effects
				(font
					(size 1.27 1.27)
				)
				(justify mirror)
			)
		)
		(property "Value" ""
			(at 0 0 0)
			(layer "B.Fab")
			(effects
				(font
					(size 1.27 1.27)
				)
				(justify mirror)
			)
		)
		(duplicate_pad_numbers_are_jumpers no)
		(fp_line
			(start 0.7874 0.4064)
			(end 0.7874 -0.4064)
			(stroke
				(width 0.1524)
				(type default)
			)
			(layer "B.SilkS")
		)
		(fp_line
			(start 0.7874 -0.4064)
			(end -0.7874 -0.4064)
			(stroke
				(width 0.1524)
				(type default)
			)
			(layer "B.SilkS")
		)
		(fp_line
			(start -0.7874 0.4064)
			(end 0.7874 0.4064)
			(stroke
				(width 0.1524)
				(type default)
			)
			(layer "B.SilkS")
		)
		(fp_line
			(start -0.7874 -0.4064)
			(end -0.7874 0.4064)
			(stroke
				(width 0.1524)
				(type default)
			)
			(layer "B.SilkS")
		)
		(fp_line
			(start 0.67945 0.3048)
			(end 0.67945 -0.305054)
			(stroke
				(width 0.1)
				(type default)
			)
			(layer "B.Fab")
		)
		(fp_line
			(start 0.67945 -0.305054)
			(end 0.12065 -0.305054)
			(stroke
				(width 0.1)
				(type default)
			)
			(layer "B.Fab")
		)
		(fp_line
			(start 0.12065 0.3048)
			(end 0.67945 0.3048)
			(stroke
				(width 0.1)
				(type default)
			)
			(layer "B.Fab")
		)
		(fp_line
			(start 0.12065 0.2794)
			(end 0.12065 0.3048)
			(stroke
				(width 0.1)
				(type default)
			)
			(layer "B.Fab")
		)
		(fp_line
			(start 0.12065 -0.2794)
			(end -0.12065 -0.2794)
			(stroke
				(width 0.1)
				(type default)
			)
			(layer "B.Fab")
		)
		(fp_line
			(start 0.12065 -0.305054)
			(end 0.12065 -0.2794)
			(stroke
				(width 0.1)
				(type default)
			)
			(layer "B.Fab")
		)
		(fp_line
			(start -0.120396 0.3048)
			(end -0.120396 0.2794)
			(stroke
				(width 0.1)
				(type default)
			)
			(layer "B.Fab")
		)
		(fp_line
			(start -0.120396 0.2794)
			(end 0.12065 0.2794)
			(stroke
				(width 0.1)
				(type default)
			)
			(layer "B.Fab")
		)
		(fp_line
			(start -0.12065 -0.2794)
			(end -0.12065 -0.3048)
			(stroke
				(width 0.1)
				(type default)
			)
			(layer "B.Fab")
		)
		(fp_line
			(start -0.12065 -0.3048)
			(end -0.67945 -0.3048)
			(stroke
				(width 0.1)
				(type default)
			)
			(layer "B.Fab")
		)
		(fp_line
			(start -0.67945 0.3048)
			(end -0.120396 0.3048)
			(stroke
				(width 0.1)
				(type default)
			)
			(layer "B.Fab")
		)
		(fp_line
			(start -0.67945 -0.3048)
			(end -0.67945 0.3048)
			(stroke
				(width 0.1)
				(type default)
			)
			(layer "B.Fab")
		)
		(pad "1" smd circle
			(at 0.40005 0)
			(size 0 0)
			(layers "B.Cu" "B.Mask" "B.Paste")
			(net "GND")
		)
		(pad "2" smd circle
			(at -0.40005 0)
			(size 0 0)
			(layers "B.Cu" "B.Mask" "B.Paste")
			(net "BIC_PECI")
		)
	)
)
